# S9S_MB_2U (Grand Teton) — schematic netlist excerpt (pin names and nets, part order shuffled) for the footprints in the layout excerpt that follows; sources: Cadence DE-HDL packaged netlist, KiCad conversion of 03242023_DA0F0TMBIJ0_F0T_Motherboard_J_brd_V01_OCP.brd

R746  Q_RES  0 5% CHIP  pkg 0402LF  page 132 : A = PD_74CB_A9 ; B = GND
R474  Q_RES  33.2 1% CHIP  pkg 0402LF  page 183 : A = FM_PCHHOT_N ; B = FM_PCHHOT_R_N

(kicad_pcb
	(version 20260206)
	(generator "pcbnew")
	(generator_version "10.0")
	(general
		(thickness 1.6)
		(legacy_teardrops no)
	)
	(paper "A4")
	(title_block
		(title "03242023_DA0F0TMBIJ0_F0T_Motherboard_J_brd_V01_OCP.brd")
		(comment 1 "Grand Teton / footprints 1020-1021 of 6105")
	)
	(layers
		(0 "F.Cu" signal "TOP")
		(4 "In1.Cu" signal "GND")
		(6 "In2.Cu" signal "IN1")
		(8 "In3.Cu" signal "GND1")
		(10 "In4.Cu" signal "IN2")
		(12 "In5.Cu" signal "GND2")
		(14 "In6.Cu" signal "IN3")
		(16 "In7.Cu" signal "GND3")
		(18 "In8.Cu" signal "VCC")
		(20 "In9.Cu" signal "VCC1")
		(22 "In10.Cu" signal "GND4")
		(24 "In11.Cu" signal "IN4")
		(26 "In12.Cu" signal "GND5")
		(28 "In13.Cu" signal "IN5")
		(30 "In14.Cu" signal "GND6")
		(32 "In15.Cu" signal "IN6")
		(34 "In16.Cu" signal "GND7")
		(2 "B.Cu" signal "BOTTOM")
		(9 "F.Adhes" user "F.Adhesive")
		(11 "B.Adhes" user "B.Adhesive")
		(13 "F.Paste" user "Package Geometry/Pastemask Top")
		(15 "B.Paste" user "Package Geometry/Pastemask Bottom")
		(5 "F.SilkS" user "Ref Des/Silkscreen Top")
		(7 "B.SilkS" user "Ref Des/Silkscreen Bottom")
		(1 "F.Mask" user "Board Geometry/Soldermask Top")
		(3 "B.Mask" user "Board Geometry/Soldermask Bottom")
		(17 "Dwgs.User" user "User.Drawings")
		(19 "Cmts.User" user "User.Comments")
		(21 "Eco1.User" user "User.Eco1")
		(23 "Eco2.User" user "User.Eco2")
		(25 "Edge.Cuts" user "Board Geometry/Outline")
		(27 "Margin" user)
		(31 "F.CrtYd" user "Package Geometry/Place Bound Top")
		(29 "B.CrtYd" user "Package Geometry/Place Bound Bottom")
		(35 "F.Fab" user "Ref Des/Assembly Top")
		(33 "B.Fab" user "Ref Des/Assembly Bottom")
	)
	(footprint ""
		(layer "F.Cu")
		(at 374.112282 -57.263792)
		(property "Reference" "R746"
			(at 0 0 0)
			(layer "F.SilkS")
			(hide yes)
			(effects
				(font
					(size 1.27 1.27)
				)
			)
		)
		(property "Value" ""
			(at 0 0 0)
			(layer "F.Fab")
			(effects
				(font
					(size 1.27 1.27)
				)
			)
		)
		(duplicate_pad_numbers_are_jumpers no)
		(fp_line
			(start -0.7874 -0.4064)
			(end 0.7874 -0.4064)
			(stroke
				(width 0.1524)
				(type default)
			)
			(layer "F.SilkS")
		)
		(fp_line
			(start -0.7874 0.4064)
			(end -0.7874 -0.4064)
			(stroke
				(width 0.1524)
				(type default)
			)
			(layer "F.SilkS")
		)
		(fp_line
			(start 0.7874 -0.4064)
			(end 0.7874 0.4064)
			(stroke
				(width 0.1524)
				(type default)
			)
			(layer "F.SilkS")
		)
		(fp_line
			(start 0.7874 0.4064)
			(end -0.7874 0.4064)
			(stroke
				(width 0.1524)
				(type default)
			)
			(layer "F.SilkS")
		)
		(fp_line
			(start -0.67945 -0.305054)
			(end -0.12065 -0.305054)
			(stroke
				(width 0.1)
				(type default)
			)
			(layer "F.Fab")
		)
		(fp_line
			(start -0.67945 0.3048)
			(end -0.67945 -0.305054)
			(stroke
				(width 0.1)
				(type default)
			)
			(layer "F.Fab")
		)
		(fp_line
			(start -0.12065 -0.305054)
			(end -0.12065 -0.2794)
			(stroke
				(width 0.1)
				(type default)
			)
			(layer "F.Fab")
		)
		(fp_line
			(start -0.12065 -0.2794)
			(end 0.12065 -0.2794)
			(stroke
				(width 0.1)
				(type default)
			)
			(layer "F.Fab")
		)
		(fp_line
			(start -0.12065 0.2794)
			(end -0.12065 0.3048)
			(stroke
				(width 0.1)
				(type default)
			)
			(layer "F.Fab")
		)
		(fp_line
			(start -0.12065 0.3048)
			(end -0.67945 0.3048)
			(stroke
				(width 0.1)
				(type default)
			)
			(layer "F.Fab")
		)
		(fp_line
			(start 0.120396 0.2794)
			(end -0.12065 0.2794)
			(stroke
				(width 0.1)
				(type default)
			)
			(layer "F.Fab")
		)
		(fp_line
			(start 0.120396 0.3048)
			(end 0.120396 0.2794)
			(stroke
				(width 0.1)
				(type default)
			)
			(layer "F.Fab")
		)
		(fp_line
			(start 0.12065 -0.3048)
			(end 0.67945 -0.3048)
			(stroke
				(width 0.1)
				(type default)
			)
			(layer "F.Fab")
		)
		(fp_line
			(start 0.12065 -0.2794)
			(end 0.12065 -0.3048)
			(stroke
				(width 0.1)
				(type default)
			)
			(layer "F.Fab")
		)
		(fp_line
			(start 0.67945 -0.3048)
			(end 0.67945 0.3048)
			(stroke
				(width 0.1)
				(type default)
			)
			(layer "F.Fab")
		)
		(fp_line
			(start 0.67945 0.3048)
			(end 0.120396 0.3048)
			(stroke
				(width 0.1)
				(type default)
			)
			(layer "F.Fab")
		)
		(pad "1" smd circle
			(at -0.40005 0)
			(size 0 0)
			(layers "F.Cu" "F.Mask" "F.Paste")
			(net "PD_74CB_A9")
		)
		(pad "2" smd circle
			(at 0.40005 0)
			(size 0 0)
			(layers "F.Cu" "F.Mask" "F.Paste")
			(net "GND")
		)
	)
	(footprint ""
		(layer "F.Cu")
		(at 307.725826 -43.589194 180)
		(property "Reference" "R474"
			(at 0 0 180)
			(layer "F.SilkS")
			(hide yes)
			(effects
				(font
					(size 1.27 1.27)
				)
			)
		)
		(property "Value" ""
			(at 0 0 180)
			(layer "F.Fab")
			(effects
				(font
					(size 1.27 1.27)
				)
			)
		)
		(duplicate_pad_numbers_are_jumpers no)
		(fp_line
			(start 0.7874 0.4064)
			(end -0.7874 0.4064)
			(stroke
				(width 0.1524)
				(type default)
			)
			(layer "F.SilkS")
		)
		(fp_line
			(start 0.7874 -0.4064)
			(end 0.7874 0.4064)
			(stroke
				(width 0.1524)
				(type default)
			)
			(layer "F.SilkS")
		)
		(fp_line
			(start -0.7874 0.4064)
			(end -0.7874 -0.4064)
			(stroke
				(width 0.1524)
				(type default)
			)
			(layer "F.SilkS")
		)
		(fp_line
			(start -0.7874 -0.4064)
			(end 0.7874 -0.4064)
			(stroke
				(width 0.1524)
				(type default)
			)
			(layer "F.SilkS")
		)
		(fp_line
			(start 0.67945 0.3048)
			(end 0.120396 0.3048)
			(stroke
				(width 0.1)
				(type default)
			)
			(layer "F.Fab")
		)
		(fp_line
			(start 0.67945 -0.3048)
			(end 0.67945 0.3048)
			(stroke
				(width 0.1)
				(type default)
			)
			(layer "F.Fab")
		)
		(fp_line
			(start 0.12065 -0.2794)
			(end 0.12065 -0.3048)
			(stroke
				(width 0.1)
				(type default)
			)
			(layer "F.Fab")
		)
		(fp_line
			(start 0.12065 -0.3048)
			(end 0.67945 -0.3048)
			(stroke
				(width 0.1)
				(type default)
			)
			(layer "F.Fab")
		)
		(fp_line
			(start 0.120396 0.3048)
			(end 0.120396 0.2794)
			(stroke
				(width 0.1)
				(type default)
			)
			(layer "F.Fab")
		)
		(fp_line
			(start 0.120396 0.2794)
			(end -0.12065 0.2794)
			(stroke
				(width 0.1)
				(type default)
			)
			(layer "F.Fab")
		)
		(fp_line
			(start -0.12065 0.3048)
			(end -0.67945 0.3048)
			(stroke
				(width 0.1)
				(type default)
			)
			(layer "F.Fab")
		)
		(fp_line
			(start -0.12065 0.2794)
			(end -0.12065 0.3048)
			(stroke
				(width 0.1)
				(type default)
			)
			(layer "F.Fab")
		)
		(fp_line
			(start -0.12065 -0.2794)
			(end 0.12065 -0.2794)
			(stroke
				(width 0.1)
				(type default)
			)
			(layer "F.Fab")
		)
		(fp_line
			(start -0.12065 -0.305054)
			(end -0.12065 -0.2794)
			(stroke
				(width 0.1)
				(type default)
			)
			(layer "F.Fab")
		)
		(fp_line
			(start -0.67945 0.3048)
			(end -0.67945 -0.305054)
			(stroke
				(width 0.1)
				(type default)
			)
			(layer "F.Fab")
		)
		(fp_line
			(start -0.67945 -0.305054)
			(end -0.12065 -0.305054)
			(stroke
				(width 0.1)
				(type default)
			)
			(layer "F.Fab")
		)
		(pad "1" smd circle
			(at -0.40005 0 180)
			(size 0 0)
			(layers "F.Cu" "F.Mask" "F.Paste")
			(net "FM_PCHHOT_N")
		)
		(pad "2" smd circle
			(at 0.40005 0 180)
			(size 0 0)
			(layers "F.Cu" "F.Mask" "F.Paste")
			(net "FM_PCHHOT_R_N")
		)
	)
)
